(kicad_pcb
	(version 20260206)
	(generator "pcbnew")
	(generator_version "10.0")
	(general
		(thickness 1.6)
		(legacy_teardrops no)
	)
	(paper "A4")
	(title_block
		(title "Wiwynn_Tioga_Pass_MB.brd")
		(comment 1 "Tioga Pass / footprints 429-430 of 4770")
	)
	(layers
		(0 "F.Cu" signal "TOP")
		(4 "In1.Cu" signal "L2GND")
		(6 "In2.Cu" signal "L3")
		(8 "In3.Cu" signal "L4GND")
		(10 "In4.Cu" signal "L5")
		(12 "In5.Cu" signal "L6GND")
		(14 "In6.Cu" signal "L7VCC")
		(16 "In7.Cu" signal "L8VCC")
		(18 "In8.Cu" signal "L9GND")
		(20 "In9.Cu" signal "L10")
		(22 "In10.Cu" signal "L11GND")
		(24 "In11.Cu" signal "L12")
		(26 "In12.Cu" signal "L13GND")
		(2 "B.Cu" signal "BOTTOM")
		(9 "F.Adhes" user "F.Adhesive")
		(11 "B.Adhes" user "B.Adhesive")
		(13 "F.Paste" user "Package Geometry/Pastemask Top")
		(15 "B.Paste" user "Package Geometry/Pastemask Bottom")
		(5 "F.SilkS" user "Ref Des/Silkscreen Top")
		(7 "B.SilkS" user "Ref Des/Silkscreen Bottom")
		(1 "F.Mask" user "Board Geometry/Soldermask Top")
		(3 "B.Mask" user "Board Geometry/Soldermask Bottom")
		(17 "Dwgs.User" user "User.Drawings")
		(19 "Cmts.User" user "User.Comments")
		(21 "Eco1.User" user "User.Eco1")
		(23 "Eco2.User" user "User.Eco2")
		(25 "Edge.Cuts" user "Board Geometry/Outline")
		(27 "Margin" user)
		(31 "F.CrtYd" user "Package Geometry/Place Bound Top")
		(29 "B.CrtYd" user "Package Geometry/Place Bound Bottom")
		(35 "F.Fab" user "Ref Des/Assembly Top")
		(33 "B.Fab" user "Ref Des/Assembly Bottom")
	)
	(footprint ""
		(layer "F.Cu")
		(at 409.35402 -20.100036)
		(property "Reference" "FB1U3"
			(at 0 0 0)
			(layer "F.SilkS")
			(hide yes)
			(effects
				(font
					(size 1.27 1.27)
				)
			)
		)
		(property "Value" ""
			(at 0 0 0)
			(layer "F.Fab")
			(effects
				(font
					(size 1.27 1.27)
				)
			)
		)
		(duplicate_pad_numbers_are_jumpers no)
		(fp_poly
			(pts
				(xy -0.47625 -0.2413) (xy 0.47625 -0.2413) (xy 0.47625 1.5113) (xy -0.47625 1.5113)
			)
			(stroke
				(width 0)
				(type default)
			)
			(fill no)
			(layer "F.CrtYd")
		)
		(fp_line
			(start -0.47625 -0.2413)
			(end 0.47625 -0.2413)
			(stroke
				(width 0.1)
				(type default)
			)
			(layer "F.Fab")
		)
		(fp_line
			(start -0.47625 1.5113)
			(end -0.47625 -0.2413)
			(stroke
				(width 0.1)
				(type default)
			)
			(layer "F.Fab")
		)
		(fp_line
			(start 0.47625 -0.2413)
			(end 0.47625 1.5113)
			(stroke
				(width 0.1)
				(type default)
			)
			(layer "F.Fab")
		)
		(fp_line
			(start 0.47625 1.5113)
			(end -0.47625 1.5113)
			(stroke
				(width 0.1)
				(type default)
			)
			(layer "F.Fab")
		)
		(pad "1" smd rect
			(at 0 0)
			(size 0.762 0.889)
			(layers "F.Cu" "F.Mask" "F.Paste")
			(net "A_P1V05_STBY_PCH_SENSOR")
		)
		(pad "2" smd rect
			(at 0 1.27)
			(size 0.762 0.889)
			(layers "F.Cu" "F.Mask" "F.Paste")
			(net "P1V05_PCH_STBY")
		)
		(zone
			(layer "F.Cu")
			(hatch none 0.5)
			(connect_pads
				(clearance 0)
			)
			(min_thickness 0.25)
			(keepout
				(tracks allowed)
				(vias not_allowed)
				(pads allowed)
				(copperpour not_allowed)
				(footprints allowed)
			)
			(placement
				(enabled no)
				(sheetname "")
			)
			(fill
				(thermal_gap 0.5)
				(thermal_bridge_width 0.5)
				(island_removal_mode 0)
			)
			(polygon
				(pts
					(xy 408.96794 -19.650456) (xy 409.73502 -19.650456) (xy 409.73502 -19.274536) (xy 408.96794 -19.274536)
				)
			)
		)
		(zone
			(layer "F.Cu")
			(hatch none 0.5)
			(connect_pads
				(clearance 0)
			)
			(min_thickness 0.25)
			(keepout
				(tracks not_allowed)
				(vias allowed)
				(pads allowed)
				(copperpour not_allowed)
				(footprints allowed)
			)
			(placement
				(enabled no)
				(sheetname "")
			)
			(fill
				(thermal_gap 0.5)
				(thermal_bridge_width 0.5)
				(island_removal_mode 0)
			)
			(polygon
				(pts
					(xy 408.96794 -19.274536) (xy 409.73502 -19.274536) (xy 409.73502 -19.650456) (xy 408.96794 -19.650456)
				)
			)
		)
	)
	(footprint ""
		(layer "F.Cu")
		(at -2.1082 -143.256 90)
		(property "Reference" "CT12"
			(at -4.191 0.89027 90)
			(unlocked yes)
			(layer "F.SilkS")
			(effects
				(font
					(size 0.7874 0.5842)
					(thickness 0.1524)
				)
				(justify left)
			)
		)
		(property "Value" ""
			(at 0 0 90)
			(layer "F.Fab")
			(effects
				(font
					(size 1.27 1.27)
				)
			)
		)
		(duplicate_pad_numbers_are_jumpers no)
		(fp_poly
			(pts
				(xy 0.3048 -0.1016) (xy 0.3048 0.9906) (xy -0.3048 0.9906) (xy -0.3048 -0.1016)
			)
			(stroke
				(width 0)
				(type default)
			)
			(fill no)
			(layer "F.CrtYd")
		)
		(fp_line
			(start 0.3048 -0.1016)
			(end -0.3048 -0.1016)
			(stroke
				(width 0.1)
				(type default)
			)
			(layer "F.Fab")
		)
		(fp_line
			(start -0.3048 -0.1016)
			(end -0.3048 0.9906)
			(stroke
				(width 0.1)
				(type default)
			)
			(layer "F.Fab")
		)
		(fp_line
			(start 0.3048 0.9906)
			(end 0.3048 -0.1016)
			(stroke
				(width 0.1)
				(type default)
			)
			(layer "F.Fab")
		)
		(fp_line
			(start -0.3048 0.9906)
			(end 0.3048 0.9906)
			(stroke
				(width 0.1)
				(type default)
			)
			(layer "F.Fab")
		)
		(pad "1" smd rect
			(at 0 0 90)
			(size 0.508 0.508)
			(layers "F.Cu" "F.Mask" "F.Paste")
			(net "VR_PVDDQ_KLM_AIREF2")
		)
		(pad "2" smd rect
			(at 0 0.889 90)
			(size 0.508 0.508)
			(layers "F.Cu" "F.Mask" "F.Paste")
			(net "GND")
		)
		(zone
			(layer "F.Cu")
			(hatch none 0.5)
			(connect_pads
				(clearance 0)
			)
			(min_thickness 0.25)
			(keepout
				(tracks allowed)
				(vias not_allowed)
				(pads allowed)
				(copperpour not_allowed)
				(footprints allowed)
			)
			(placement
				(enabled no)
				(sheetname "")
			)
			(fill
				(thermal_gap 0.5)
				(thermal_bridge_width 0.5)
				(island_removal_mode 0)
			)
			(polygon
				(pts
					(xy -1.8542 -143.002) (xy -1.8542 -143.51) (xy -1.4732 -143.51) (xy -1.4732 -143.002)
				)
			)
		)
		(zone
			(layer "F.Cu")
			(hatch none 0.5)
			(connect_pads
				(clearance 0)
			)
			(min_thickness 0.25)
			(keepout
				(tracks not_allowed)
				(vias allowed)
				(pads allowed)
				(copperpour not_allowed)
				(footprints allowed)
			)
			(placement
				(enabled no)
				(sheetname "")
			)
			(fill
				(thermal_gap 0.5)
				(thermal_bridge_width 0.5)
				(island_removal_mode 0)
			)
			(polygon
				(pts
					(xy -1.4732 -143.002) (xy -1.4732 -143.51) (xy -1.8542 -143.51) (xy -1.8542 -143.002)
				)
			)
		)
	)
)
